FILE_TYPE = MACRO_DRAWING;
SET COLOR_WIRE YELLOW;
SET COLOR_PROP MONO;
SET COLOR_DOT WHITE;
SET COLOR_ARC YELLOW;
SET COLOR_BODY GREEN;
SET COLOR_NOTE MONO;
SET PROP_DISPLAY VALUE;
SET PAGE_NUMBER P39;
FORCEADD OFFPAGE..1
(-6150 1900);
FORCEPROP 2 LAST $XR0 97 
J 0
(-6371 1900);
DISPLAY 0.638298 (-6371 1900);
PAINT MONO (-6371 1900);
FORCEPROP 2 LAST CDS_LIB mstr_standard
J 0
(-6150 1900);
PAINT ORANGE (-6150 1900);
DISPLAY INVISIBLE (-6150 1900);
FORCEPROP 1 LAST OFFPAGE TRUE
J 0
(-5825 1775);
DISPLAY 0.872340 (-5825 1775);
PAINT GREEN (-5825 1775);
DISPLAY INVISIBLE (-5825 1775);
FORCEPROP 1 LAST COMMENT_BODY TRUE
J 0
(-6025 1800);
DISPLAY 0.872340 (-6025 1800);
PAINT GREEN (-6025 1800);
DISPLAY INVISIBLE (-6025 1800);
FORCEPROP 2 LAST PATH I122
J 0
(-6100 1975);
DISPLAY 1.021277 (-6100 1975);
PAINT ORANGE (-6100 1975);
DISPLAY INVISIBLE (-6100 1975);
FORCEADD VCC_CORE..1
(-2250 4025);
FORCEPROP 3 LASTPIN (-2250 3975) SIG_NAME PVCCMCP_CPU0\g
J 0
(-2240 3985);
DISPLAY 0.659574 (-2240 3985);
PAINT MONO (-2240 3985);
DISPLAY INVISIBLE (-2240 3985);
FORCEPROP 1 LAST HDL_POWER PVCCMCP_CPU0
J 1
(-2250 4075);
DISPLAY 0.617021 (-2250 4075);
PAINT GREEN (-2250 4075);
FORCEPROP 2 LAST CDS_LIB mstr_symbols
J 0
(-2250 4025);
PAINT ORANGE (-2250 4025);
DISPLAY INVISIBLE (-2250 4025);
FORCEPROP 1 LAST PATH I123
J 0
(-2200 4050);
DISPLAY 0.872340 (-2200 4050);
PAINT AQUA (-2200 4050);
DISPLAY INVISIBLE (-2200 4050);
FORCEADD VCC_CORE..1
(-6025 2875);
FORCEPROP 3 LASTPIN (-6025 2825) SIG_NAME PVCCMCP_CPU0\g
J 0
(-6015 2835);
DISPLAY 0.659574 (-6015 2835);
PAINT MONO (-6015 2835);
DISPLAY INVISIBLE (-6015 2835);
FORCEPROP 1 LAST HDL_POWER PVCCMCP_CPU0
J 1
(-6025 2925);
DISPLAY 0.617021 (-6025 2925);
PAINT GREEN (-6025 2925);
FORCEPROP 2 LAST CDS_LIB mstr_symbols
J 0
(-6025 2875);
PAINT ORANGE (-6025 2875);
DISPLAY INVISIBLE (-6025 2875);
FORCEPROP 1 LAST PATH I125
J 0
(-5975 2900);
DISPLAY 0.872340 (-5975 2900);
PAINT AQUA (-5975 2900);
DISPLAY INVISIBLE (-5975 2900);
FORCEADD VCC_CORE..1
(-6825 1950);
FORCEPROP 3 LASTPIN (-6825 1900) SIG_NAME PVCCMCP_CPU0\g
J 0
(-6815 1910);
DISPLAY 0.659574 (-6815 1910);
PAINT MONO (-6815 1910);
DISPLAY INVISIBLE (-6815 1910);
FORCEPROP 1 LAST HDL_POWER PVCCMCP_CPU0
J 1
(-6825 2000);
DISPLAY 0.617021 (-6825 2000);
PAINT GREEN (-6825 2000);
FORCEPROP 2 LAST CDS_LIB mstr_symbols
J 0
(-6825 1950);
PAINT ORANGE (-6825 1950);
DISPLAY INVISIBLE (-6825 1950);
FORCEPROP 1 LAST PATH I126
J 0
(-6775 1975);
DISPLAY 0.872340 (-6775 1975);
PAINT AQUA (-6775 1975);
DISPLAY INVISIBLE (-6775 1975);
FORCEADD SKX_EXT_B..22
(-4250 2550);
FORCEPROP 1 LAST LOCATION U5D1
J 0
(-5250 4200);
DISPLAY 0.617021 (-5250 4200);
PAINT AQUA (-5250 4200);
FORCEPROP 1 LAST PART_NUMBER TBD
J 0
(-5250 750);
DISPLAY 0.617021 (-5250 750);
PAINT BLUE (-5250 750);
FORCEPROP 1 LAST MATERIAL IC
J 0
(-5250 4150);
DISPLAY 0.617021 (-5250 4150);
PAINT SKYBLUE (-5250 4150);
FORCEPROP 2 LASTPIN (-5300 2450) $PN CG76
J 2
(-5310 2460);
DISPLAY 0.617021 (-5310 2460);
PAINT ORANGE (-5310 2460);
FORCEPROP 2 LASTPIN (-5300 2000) $PN BF5
J 2
(-5310 2010);
DISPLAY 0.617021 (-5310 2010);
PAINT ORANGE (-5310 2010);
FORCEPROP 2 LASTPIN (-5300 2500) $PN CE76
J 2
(-5310 2510);
DISPLAY 0.617021 (-5310 2510);
PAINT ORANGE (-5310 2510);
FORCEPROP 2 LASTPIN (-5300 2050) $PN BH5
J 2
(-5310 2060);
DISPLAY 0.617021 (-5310 2060);
PAINT ORANGE (-5310 2060);
FORCEPROP 2 LASTPIN (-5300 3950) $PN CN6
J 2
(-5310 3960);
DISPLAY 0.617021 (-5310 3960);
PAINT ORANGE (-5310 3960);
FORCEPROP 2 LASTPIN (-5300 3900) $PN CU12
J 2
(-5310 3910);
DISPLAY 0.617021 (-5310 3910);
PAINT ORANGE (-5310 3910);
FORCEPROP 2 LASTPIN (-5300 3800) $PN CV21
J 2
(-5310 3810);
DISPLAY 0.617021 (-5310 3810);
PAINT ORANGE (-5310 3810);
FORCEPROP 2 LASTPIN (-5300 3750) $PN CU18
J 2
(-5310 3760);
DISPLAY 0.617021 (-5310 3760);
PAINT ORANGE (-5310 3760);
FORCEPROP 2 LASTPIN (-5300 3700) $PN CY17
J 2
(-5310 3710);
DISPLAY 0.617021 (-5310 3710);
PAINT ORANGE (-5310 3710);
FORCEPROP 2 LASTPIN (-5300 3650) $PN DC18
J 2
(-5310 3660);
DISPLAY 0.617021 (-5310 3660);
PAINT ORANGE (-5310 3660);
FORCEPROP 2 LASTPIN (-5300 3600) $PN DE14
J 2
(-5310 3610);
DISPLAY 0.617021 (-5310 3610);
PAINT ORANGE (-5310 3610);
FORCEPROP 2 LASTPIN (-5300 3550) $PN CP13
J 2
(-5310 3560);
DISPLAY 0.617021 (-5310 3560);
PAINT ORANGE (-5310 3560);
FORCEPROP 2 LASTPIN (-5300 3500) $PN CL20
J 2
(-5310 3510);
DISPLAY 0.617021 (-5310 3510);
PAINT ORANGE (-5310 3510);
FORCEPROP 2 LASTPIN (-5300 3450) $PN CG14
J 2
(-5310 3460);
DISPLAY 0.617021 (-5310 3460);
PAINT ORANGE (-5310 3460);
FORCEPROP 2 LASTPIN (-5300 3350) $PN CF5
J 2
(-5310 3360);
DISPLAY 0.617021 (-5310 3360);
PAINT ORANGE (-5310 3360);
FORCEPROP 2 LASTPIN (-5300 3300) $PN DK21
J 2
(-5310 3310);
DISPLAY 0.617021 (-5310 3310);
PAINT ORANGE (-5310 3310);
FORCEPROP 2 LASTPIN (-5300 3250) $PN BE24
J 2
(-5310 3260);
DISPLAY 0.617021 (-5310 3260);
PAINT ORANGE (-5310 3260);
FORCEPROP 2 LASTPIN (-5300 3200) $PN AT7
J 2
(-5310 3210);
DISPLAY 0.617021 (-5310 3210);
PAINT ORANGE (-5310 3210);
FORCEPROP 2 LASTPIN (-5300 3150) $PN AT5
J 2
(-5310 3160);
DISPLAY 0.617021 (-5310 3160);
PAINT ORANGE (-5310 3160);
FORCEPROP 2 LASTPIN (-5300 3100) $PN AM5
J 2
(-5310 3110);
DISPLAY 0.617021 (-5310 3110);
PAINT ORANGE (-5310 3110);
FORCEPROP 2 LASTPIN (-5300 3050) $PN DV11
J 2
(-5310 3060);
DISPLAY 0.617021 (-5310 3060);
PAINT ORANGE (-5310 3060);
FORCEPROP 2 LASTPIN (-5300 3000) $PN AF5
J 2
(-5310 3010);
DISPLAY 0.617021 (-5310 3010);
PAINT ORANGE (-5310 3010);
FORCEPROP 2 LASTPIN (-5300 2950) $PN AE10
J 2
(-5310 2960);
DISPLAY 0.617021 (-5310 2960);
PAINT ORANGE (-5310 2960);
FORCEPROP 2 LASTPIN (-5300 2900) $PN EE10
J 2
(-5310 2910);
DISPLAY 0.617021 (-5310 2910);
PAINT ORANGE (-5310 2910);
FORCEPROP 2 LASTPIN (-5300 2800) $PN CL26
J 2
(-5310 2810);
DISPLAY 0.617021 (-5310 2810);
PAINT ORANGE (-5310 2810);
FORCEPROP 2 LASTPIN (-5300 2750) $PN CM23
J 2
(-5310 2760);
DISPLAY 0.617021 (-5310 2760);
PAINT ORANGE (-5310 2760);
FORCEPROP 2 LASTPIN (-5300 2700) $PN CM25
J 2
(-5310 2710);
DISPLAY 0.617021 (-5310 2710);
PAINT ORANGE (-5310 2710);
FORCEPROP 2 LASTPIN (-5300 2650) $PN CN22
J 2
(-5310 2660);
DISPLAY 0.617021 (-5310 2660);
PAINT ORANGE (-5310 2660);
FORCEPROP 2 LASTPIN (-5300 2600) $PN CN24
J 2
(-5310 2610);
DISPLAY 0.617021 (-5310 2610);
PAINT ORANGE (-5310 2610);
FORCEPROP 2 LASTPIN (-5300 1900) $PN CN28
J 2
(-5310 1910);
DISPLAY 0.617021 (-5310 1910);
PAINT ORANGE (-5310 1910);
FORCEPROP 2 LASTPIN (-5300 1850) $PN CP23
J 2
(-5310 1860);
DISPLAY 0.617021 (-5310 1860);
PAINT ORANGE (-5310 1860);
FORCEPROP 2 LASTPIN (-5300 1800) $PN CP31
J 2
(-5310 1810);
DISPLAY 0.617021 (-5310 1810);
PAINT ORANGE (-5310 1810);
FORCEPROP 2 LASTPIN (-5300 1750) $PN CR60
J 2
(-5310 1760);
DISPLAY 0.617021 (-5310 1760);
PAINT ORANGE (-5310 1760);
FORCEPROP 2 LASTPIN (-5300 1700) $PN CT23
J 2
(-5310 1710);
DISPLAY 0.617021 (-5310 1710);
PAINT ORANGE (-5310 1710);
FORCEPROP 2 LASTPIN (-5300 1650) $PN CT5
J 2
(-5310 1660);
DISPLAY 0.617021 (-5310 1660);
PAINT ORANGE (-5310 1660);
FORCEPROP 2 LASTPIN (-5300 1600) $PN CT69
J 2
(-5310 1610);
DISPLAY 0.617021 (-5310 1610);
PAINT ORANGE (-5310 1610);
FORCEPROP 2 LASTPIN (-5300 1550) $PN CU24
J 2
(-5310 1560);
DISPLAY 0.617021 (-5310 1560);
PAINT ORANGE (-5310 1560);
FORCEPROP 2 LASTPIN (-5300 1500) $PN CU6
J 2
(-5310 1510);
DISPLAY 0.617021 (-5310 1510);
PAINT ORANGE (-5310 1510);
FORCEPROP 2 LASTPIN (-5300 1450) $PN CU60
J 2
(-5310 1460);
DISPLAY 0.617021 (-5310 1460);
PAINT ORANGE (-5310 1460);
FORCEPROP 2 LASTPIN (-5300 1400) $PN CV23
J 2
(-5310 1410);
DISPLAY 0.617021 (-5310 1410);
PAINT ORANGE (-5310 1410);
FORCEPROP 2 LASTPIN (-5300 1350) $PN CV69
J 2
(-5310 1360);
DISPLAY 0.617021 (-5310 1360);
PAINT ORANGE (-5310 1360);
FORCEPROP 2 LASTPIN (-5300 1300) $PN CW22
J 2
(-5310 1310);
DISPLAY 0.617021 (-5310 1310);
PAINT ORANGE (-5310 1310);
FORCEPROP 2 LASTPIN (-5300 1250) $PN CW24
J 2
(-5310 1260);
DISPLAY 0.617021 (-5310 1260);
PAINT ORANGE (-5310 1260);
FORCEPROP 2 LASTPIN (-5300 1200) $PN CW60
J 2
(-5310 1210);
DISPLAY 0.617021 (-5310 1210);
PAINT ORANGE (-5310 1210);
FORCEPROP 2 LASTPIN (-3200 3950) $PN CW62
J 0
(-3190 3960);
DISPLAY 0.617021 (-3190 3960);
PAINT ORANGE (-3190 3960);
FORCEPROP 2 LASTPIN (-3200 3900) $PN CY23
J 0
(-3190 3910);
DISPLAY 0.617021 (-3190 3910);
PAINT ORANGE (-3190 3910);
FORCEPROP 2 LASTPIN (-3200 3850) $PN CY25
J 0
(-3190 3860);
DISPLAY 0.617021 (-3190 3860);
PAINT ORANGE (-3190 3860);
FORCEPROP 2 LASTPIN (-3200 3800) $PN CY39
J 0
(-3190 3810);
DISPLAY 0.617021 (-3190 3810);
PAINT ORANGE (-3190 3810);
FORCEPROP 2 LASTPIN (-3200 3750) $PN CY53
J 0
(-3190 3760);
DISPLAY 0.617021 (-3190 3760);
PAINT ORANGE (-3190 3760);
FORCEPROP 2 LASTPIN (-3200 3700) $PN CY57
J 0
(-3190 3710);
DISPLAY 0.617021 (-3190 3710);
PAINT ORANGE (-3190 3710);
FORCEPROP 2 LASTPIN (-3200 3650) $PN CY63
J 0
(-3190 3660);
DISPLAY 0.617021 (-3190 3660);
PAINT ORANGE (-3190 3660);
FORCEPROP 2 LASTPIN (-3200 3600) $PN CY73
J 0
(-3190 3610);
DISPLAY 0.617021 (-3190 3610);
PAINT ORANGE (-3190 3610);
FORCEPROP 2 LASTPIN (-3200 3550) $PN DA24
J 0
(-3190 3560);
DISPLAY 0.617021 (-3190 3560);
PAINT ORANGE (-3190 3560);
FORCEPROP 2 LASTPIN (-3200 3500) $PN DA40
J 0
(-3190 3510);
DISPLAY 0.617021 (-3190 3510);
PAINT ORANGE (-3190 3510);
FORCEPROP 2 LASTPIN (-3200 3450) $PN DA52
J 0
(-3190 3460);
DISPLAY 0.617021 (-3190 3460);
PAINT ORANGE (-3190 3460);
FORCEPROP 2 LASTPIN (-3200 3400) $PN DA54
J 0
(-3190 3410);
DISPLAY 0.617021 (-3190 3410);
PAINT ORANGE (-3190 3410);
FORCEPROP 2 LASTPIN (-3200 3350) $PN DA56
J 0
(-3190 3360);
DISPLAY 0.617021 (-3190 3360);
PAINT ORANGE (-3190 3360);
FORCEPROP 2 LASTPIN (-3200 3300) $PN DC46
J 0
(-3190 3310);
DISPLAY 0.617021 (-3190 3310);
PAINT ORANGE (-3190 3310);
FORCEPROP 2 LASTPIN (-3200 3250) $PN DC52
J 0
(-3190 3260);
DISPLAY 0.617021 (-3190 3260);
PAINT ORANGE (-3190 3260);
FORCEPROP 2 LASTPIN (-3200 3200) $PN DD51
J 0
(-3190 3210);
DISPLAY 0.617021 (-3190 3210);
PAINT ORANGE (-3190 3210);
FORCEPROP 2 LASTPIN (-3200 3150) $PN DG36
J 0
(-3190 3160);
DISPLAY 0.617021 (-3190 3160);
PAINT ORANGE (-3190 3160);
FORCEPROP 2 LASTPIN (-3200 3100) $PN DG64
J 0
(-3190 3110);
DISPLAY 0.617021 (-3190 3110);
PAINT ORANGE (-3190 3110);
FORCEPROP 2 LASTPIN (-3200 3050) $PN DH65
J 0
(-3190 3060);
DISPLAY 0.617021 (-3190 3060);
PAINT ORANGE (-3190 3060);
FORCEPROP 2 LASTPIN (-3200 3000) $PN DJ36
J 0
(-3190 3010);
DISPLAY 0.617021 (-3190 3010);
PAINT ORANGE (-3190 3010);
FORCEPROP 2 LASTPIN (-3200 2950) $PN DJ66
J 0
(-3190 2960);
DISPLAY 0.617021 (-3190 2960);
PAINT ORANGE (-3190 2960);
FORCEPROP 2 LASTPIN (-3200 2900) $PN DK15
J 0
(-3190 2910);
DISPLAY 0.617021 (-3190 2910);
PAINT ORANGE (-3190 2910);
FORCEPROP 2 LASTPIN (-3200 2850) $PN DK37
J 0
(-3190 2860);
DISPLAY 0.617021 (-3190 2860);
PAINT ORANGE (-3190 2860);
FORCEPROP 2 LASTPIN (-3200 2800) $PN DK65
J 0
(-3190 2810);
DISPLAY 0.617021 (-3190 2810);
PAINT ORANGE (-3190 2810);
FORCEPROP 2 LASTPIN (-3200 2750) $PN DK67
J 0
(-3190 2760);
DISPLAY 0.617021 (-3190 2760);
PAINT ORANGE (-3190 2760);
FORCEPROP 2 LASTPIN (-3200 2700) $PN DL38
J 0
(-3190 2710);
DISPLAY 0.617021 (-3190 2710);
PAINT ORANGE (-3190 2710);
FORCEPROP 2 LASTPIN (-3200 2650) $PN DL66
J 0
(-3190 2660);
DISPLAY 0.617021 (-3190 2660);
PAINT ORANGE (-3190 2660);
FORCEPROP 2 LASTPIN (-3200 2600) $PN DM67
J 0
(-3190 2610);
DISPLAY 0.617021 (-3190 2610);
PAINT ORANGE (-3190 2610);
FORCEPROP 2 LASTPIN (-3200 2550) $PN DN62
J 0
(-3190 2560);
DISPLAY 0.617021 (-3190 2560);
PAINT ORANGE (-3190 2560);
FORCEPROP 2 LASTPIN (-3200 2500) $PN DN66
J 0
(-3190 2510);
DISPLAY 0.617021 (-3190 2510);
PAINT ORANGE (-3190 2510);
FORCEPROP 2 LASTPIN (-3200 2450) $PN DP17
J 0
(-3190 2460);
DISPLAY 0.617021 (-3190 2460);
PAINT ORANGE (-3190 2460);
FORCEPROP 2 LASTPIN (-3200 2400) $PN DP65
J 0
(-3190 2410);
DISPLAY 0.617021 (-3190 2410);
PAINT ORANGE (-3190 2410);
FORCEPROP 2 LASTPIN (-3200 2350) $PN DR44
J 0
(-3190 2360);
DISPLAY 0.617021 (-3190 2360);
PAINT ORANGE (-3190 2360);
FORCEPROP 2 LASTPIN (-3200 2300) $PN DT71
J 0
(-3190 2310);
DISPLAY 0.617021 (-3190 2310);
PAINT ORANGE (-3190 2310);
FORCEPROP 2 LASTPIN (-3200 2250) $PN DU44
J 0
(-3190 2260);
DISPLAY 0.617021 (-3190 2260);
PAINT ORANGE (-3190 2260);
FORCEPROP 2 LASTPIN (-3200 2200) $PN DV61
J 0
(-3190 2210);
DISPLAY 0.617021 (-3190 2210);
PAINT ORANGE (-3190 2210);
FORCEPROP 2 LASTPIN (-3200 2150) $PN DV71
J 0
(-3190 2160);
DISPLAY 0.617021 (-3190 2160);
PAINT ORANGE (-3190 2160);
FORCEPROP 2 LASTPIN (-3200 2100) $PN DW44
J 0
(-3190 2110);
DISPLAY 0.617021 (-3190 2110);
PAINT ORANGE (-3190 2110);
FORCEPROP 2 LASTPIN (-3200 2050) $PN DW46
J 0
(-3190 2060);
DISPLAY 0.617021 (-3190 2060);
PAINT ORANGE (-3190 2060);
FORCEPROP 2 LASTPIN (-3200 2000) $PN DY3
J 0
(-3190 2010);
DISPLAY 0.617021 (-3190 2010);
PAINT ORANGE (-3190 2010);
FORCEPROP 2 LASTPIN (-3200 1950) $PN EA4
J 0
(-3190 1960);
DISPLAY 0.617021 (-3190 1960);
PAINT ORANGE (-3190 1960);
FORCEPROP 2 LASTPIN (-3200 1900) $PN EA44
J 0
(-3190 1910);
DISPLAY 0.617021 (-3190 1910);
PAINT ORANGE (-3190 1910);
FORCEPROP 2 LASTPIN (-3200 1850) $PN EB3
J 0
(-3190 1860);
DISPLAY 0.617021 (-3190 1860);
PAINT ORANGE (-3190 1860);
FORCEPROP 2 LASTPIN (-3200 1800) $PN EB5
J 0
(-3190 1810);
DISPLAY 0.617021 (-3190 1810);
PAINT ORANGE (-3190 1810);
FORCEPROP 2 LASTPIN (-3200 1750) $PN EB85
J 0
(-3190 1760);
DISPLAY 0.617021 (-3190 1760);
PAINT ORANGE (-3190 1760);
FORCEPROP 2 LASTPIN (-3200 1700) $PN EC16
J 0
(-3190 1710);
DISPLAY 0.617021 (-3190 1710);
PAINT ORANGE (-3190 1710);
FORCEPROP 2 LASTPIN (-3200 1650) $PN EC4
J 0
(-3190 1660);
DISPLAY 0.617021 (-3190 1660);
PAINT ORANGE (-3190 1660);
FORCEPROP 2 LASTPIN (-3200 1600) $PN EC44
J 0
(-3190 1610);
DISPLAY 0.617021 (-3190 1610);
PAINT ORANGE (-3190 1610);
FORCEPROP 2 LASTPIN (-3200 1550) $PN EC84
J 0
(-3190 1560);
DISPLAY 0.617021 (-3190 1560);
PAINT ORANGE (-3190 1560);
FORCEPROP 2 LASTPIN (-3200 1500) $PN ED45
J 0
(-3190 1510);
DISPLAY 0.617021 (-3190 1510);
PAINT ORANGE (-3190 1510);
FORCEPROP 2 LASTPIN (-3200 1450) $PN ED5
J 0
(-3190 1460);
DISPLAY 0.617021 (-3190 1460);
PAINT ORANGE (-3190 1460);
FORCEPROP 2 LASTPIN (-3200 1400) $PN ED83
J 0
(-3190 1410);
DISPLAY 0.617021 (-3190 1410);
PAINT ORANGE (-3190 1410);
FORCEPROP 2 LASTPIN (-3200 1350) $PN EE16
J 0
(-3190 1360);
DISPLAY 0.617021 (-3190 1360);
PAINT ORANGE (-3190 1360);
FORCEPROP 2 LASTPIN (-3200 1300) $PN EE46
J 0
(-3190 1310);
DISPLAY 0.617021 (-3190 1310);
PAINT ORANGE (-3190 1310);
FORCEPROP 2 LASTPIN (-3200 1250) $PN EE6
J 0
(-3190 1260);
DISPLAY 0.617021 (-3190 1260);
PAINT ORANGE (-3190 1260);
FORCEPROP 2 LASTPIN (-3200 1200) $PN EE82
J 0
(-3190 1210);
DISPLAY 0.617021 (-3190 1210);
PAINT ORANGE (-3190 1210);
FORCEPROP 2 LASTPIN (-3200 1150) $PN EE84
J 0
(-3190 1160);
DISPLAY 0.617021 (-3190 1160);
PAINT ORANGE (-3190 1160);
FORCEPROP 2 LASTPIN (-3200 1100) $PN EF47
J 0
(-3190 1110);
DISPLAY 0.617021 (-3190 1110);
PAINT ORANGE (-3190 1110);
FORCEPROP 2 LASTPIN (-3200 1050) $PN EF77
J 0
(-3190 1060);
DISPLAY 0.617021 (-3190 1060);
PAINT ORANGE (-3190 1060);
FORCEPROP 2 LASTPIN (-3200 1000) $PN EF81
J 0
(-3190 1010);
DISPLAY 0.617021 (-3190 1010);
PAINT ORANGE (-3190 1010);
FORCEPROP 2 LASTPIN (-3200 950) $PN EF83
J 0
(-3190 960);
DISPLAY 0.617021 (-3190 960);
PAINT ORANGE (-3190 960);
FORCEPROP 2 LASTPIN (-5300 2300) $PN BL16
J 2
(-5310 2310);
DISPLAY 0.617021 (-5310 2310);
PAINT ORANGE (-5310 2310);
FORCEPROP 2 LASTPIN (-5300 2200) $PN BT17
J 2
(-5310 2210);
DISPLAY 0.617021 (-5310 2210);
PAINT ORANGE (-5310 2210);
FORCEPROP 2 LASTPIN (-5300 2150) $PN BU16
J 2
(-5310 2160);
DISPLAY 0.617021 (-5310 2160);
PAINT ORANGE (-5310 2160);
FORCEPROP 2 LASTPIN (-5300 2350) $PN BN16
J 2
(-5310 2360);
DISPLAY 0.617021 (-5310 2360);
PAINT ORANGE (-5310 2360);
FORCEPROP 1 LAST PACK_TYPE BGA1
J 0
(-5250 4250);
PAINT SKYBLUE (-5250 4250);
DISPLAY INVISIBLE (-5250 4250);
FORCEPROP 2 LAST SEC_TYPE BGA1
J 0
(-5250 4250);
DISPLAY 1.021277 (-5250 4250);
PAINT ORANGE (-5250 4250);
DISPLAY INVISIBLE (-5250 4250);
FORCEPROP 2 LAST CDS_LIB chpset_lib
J 0
(-4250 2550);
PAINT ORANGE (-4250 2550);
DISPLAY INVISIBLE (-4250 2550);
FORCEPROP 2 LAST SEC 22
J 0
(-5250 4250);
DISPLAY 0.680851 (-5250 4250);
PAINT MONO (-5250 4250);
DISPLAY INVISIBLE (-5250 4250);
FORCEPROP 2 LAST CDS_LOCATION U5D1
J 0
(-5250 4200);
DISPLAY 0.617021 (-5250 4200);
PAINT AQUA (-5250 4200);
DISPLAY INVISIBLE (-5250 4200);
FORCEPROP 1 LAST PATH I127
J 0
(-4250 4150);
PAINT GREEN (-4250 4150);
DISPLAY INVISIBLE (-4250 4150);
FORCEPROP 0 LAST ROOM CPU0
J 0
(-5250 4300);
DISPLAY 1.021277 (-5250 4300);
PAINT ORANGE (-5250 4300);
DISPLAY INVISIBLE (-5250 4300);
FORCEADD PVCCIO_CPU0..1
(-5650 4175);
FORCEPROP 3 LASTPIN (-5650 4125) SIG_NAME PVCCIO_CPU0\g
J 0
(-5640 4135);
DISPLAY 0.659574 (-5640 4135);
PAINT MONO (-5640 4135);
DISPLAY INVISIBLE (-5640 4135);
FORCEPROP 1 LAST VOLTAGE 1.1V
J 0
(-5695 4132);
DISPLAY 0.340426 (-5695 4132);
PAINT SKYBLUE (-5695 4132);
DISPLAY INVISIBLE (-5695 4132);
FORCEPROP 2 LAST CDS_LIB mstr_symbols
J 0
(-5650 4175);
PAINT ORANGE (-5650 4175);
DISPLAY INVISIBLE (-5650 4175);
FORCEPROP 1 LAST BODY_TYPE PLUMBING
J 0
(-5695 4132);
DISPLAY 0.340426 (-5695 4132);
PAINT GREEN (-5695 4132);
DISPLAY INVISIBLE (-5695 4132);
FORCEPROP 1 LAST PATH I23
J 0
(-5600 4200);
DISPLAY 0.872340 (-5600 4200);
PAINT AQUA (-5600 4200);
DISPLAY INVISIBLE (-5600 4200);
FORCEPROP 1 LAST HDL_POWER PVCCIO_CPU0
J 1
(-5650 4225);
DISPLAY 0.872340 (-5650 4225);
PAINT GREEN (-5650 4225);
DISPLAY INVISIBLE (-5650 4225);
FORCEADD OFFPAGE..5
(-6175 2500);
FORCEPROP 2 LAST $XR0 205 
J 0
(-6460 2500);
DISPLAY 0.638298 (-6460 2500);
PAINT MONO (-6460 2500);
FORCEPROP 2 LAST CDS_LIB mstr_standard
J 0
(-6175 2500);
DISPLAY 0.489362 (-6175 2500);
PAINT ORANGE (-6175 2500);
DISPLAY INVISIBLE (-6175 2500);
FORCEPROP 1 LAST OFFPAGE TRUE
J 0
(-5850 2375);
PAINT GREEN (-5850 2375);
DISPLAY INVISIBLE (-5850 2375);
FORCEPROP 1 LAST COMMENT_BODY TRUE
J 0
(-6075 2425);
DISPLAY 0.680851 (-6075 2425);
PAINT PEACH (-6075 2425);
DISPLAY INVISIBLE (-6075 2425);
FORCEPROP 2 LAST PATH I33
J 0
(-6450 2550);
DISPLAY 1.021277 (-6450 2550);
PAINT ORANGE (-6450 2550);
DISPLAY INVISIBLE (-6450 2550);
FORCEADD OFFPAGE..5
(-6175 2450);
FORCEPROP 2 LAST $XR0 205 
J 0
(-6460 2450);
DISPLAY 0.638298 (-6460 2450);
PAINT MONO (-6460 2450);
FORCEPROP 2 LAST CDS_LIB mstr_standard
J 0
(-6175 2450);
DISPLAY 0.489362 (-6175 2450);
PAINT ORANGE (-6175 2450);
DISPLAY INVISIBLE (-6175 2450);
FORCEPROP 1 LAST OFFPAGE TRUE
J 0
(-5850 2325);
PAINT GREEN (-5850 2325);
DISPLAY INVISIBLE (-5850 2325);
FORCEPROP 1 LAST COMMENT_BODY TRUE
J 0
(-6075 2375);
DISPLAY 0.680851 (-6075 2375);
PAINT PEACH (-6075 2375);
DISPLAY INVISIBLE (-6075 2375);
FORCEPROP 2 LAST PATH I34
J 0
(-6450 2500);
DISPLAY 1.021277 (-6450 2500);
PAINT ORANGE (-6450 2500);
DISPLAY INVISIBLE (-6450 2500);
FORCEADD OFFPAGE..5
(-6400 2350);
FORCEPROP 2 LAST $XR0 194 
J 0
(-6685 2350);
DISPLAY 0.638298 (-6685 2350);
PAINT MONO (-6685 2350);
FORCEPROP 2 LAST CDS_LIB mstr_standard
J 0
(-6400 2350);
DISPLAY 0.489362 (-6400 2350);
PAINT ORANGE (-6400 2350);
DISPLAY INVISIBLE (-6400 2350);
FORCEPROP 1 LAST OFFPAGE TRUE
J 0
(-6075 2225);
PAINT GREEN (-6075 2225);
DISPLAY INVISIBLE (-6075 2225);
FORCEPROP 1 LAST COMMENT_BODY TRUE
J 0
(-6300 2275);
DISPLAY 0.680851 (-6300 2275);
PAINT PEACH (-6300 2275);
DISPLAY INVISIBLE (-6300 2275);
FORCEPROP 2 LAST PATH I35
J 0
(-6675 2400);
DISPLAY 1.021277 (-6675 2400);
PAINT ORANGE (-6675 2400);
DISPLAY INVISIBLE (-6675 2400);
FORCEADD OFFPAGE..5
(-6400 2300);
FORCEPROP 2 LAST $XR0 194 
J 0
(-6685 2300);
DISPLAY 0.638298 (-6685 2300);
PAINT MONO (-6685 2300);
FORCEPROP 2 LAST CDS_LIB mstr_standard
J 0
(-6400 2300);
DISPLAY 0.489362 (-6400 2300);
PAINT ORANGE (-6400 2300);
DISPLAY INVISIBLE (-6400 2300);
FORCEPROP 1 LAST OFFPAGE TRUE
J 0
(-6075 2175);
PAINT GREEN (-6075 2175);
DISPLAY INVISIBLE (-6075 2175);
FORCEPROP 1 LAST COMMENT_BODY TRUE
J 0
(-6300 2225);
DISPLAY 0.680851 (-6300 2225);
PAINT PEACH (-6300 2225);
DISPLAY INVISIBLE (-6300 2225);
FORCEPROP 2 LAST PATH I36
J 0
(-6675 2350);
DISPLAY 1.021277 (-6675 2350);
PAINT ORANGE (-6675 2350);
DISPLAY INVISIBLE (-6675 2350);
FORCEADD OFFPAGE..5
(-6375 2200);
FORCEPROP 2 LAST $XR0 194 
J 0
(-6660 2200);
DISPLAY 0.638298 (-6660 2200);
PAINT MONO (-6660 2200);
FORCEPROP 2 LAST CDS_LIB mstr_standard
J 0
(-6375 2200);
DISPLAY 0.489362 (-6375 2200);
PAINT ORANGE (-6375 2200);
DISPLAY INVISIBLE (-6375 2200);
FORCEPROP 1 LAST OFFPAGE TRUE
J 0
(-6050 2075);
PAINT GREEN (-6050 2075);
DISPLAY INVISIBLE (-6050 2075);
FORCEPROP 1 LAST COMMENT_BODY TRUE
J 0
(-6275 2125);
DISPLAY 0.680851 (-6275 2125);
PAINT PEACH (-6275 2125);
DISPLAY INVISIBLE (-6275 2125);
FORCEPROP 2 LAST PATH I37
J 0
(-6650 2250);
DISPLAY 1.021277 (-6650 2250);
PAINT ORANGE (-6650 2250);
DISPLAY INVISIBLE (-6650 2250);
FORCEADD OFFPAGE..5
(-6375 2150);
FORCEPROP 2 LAST $XR0 194 
J 0
(-6660 2150);
DISPLAY 0.638298 (-6660 2150);
PAINT MONO (-6660 2150);
FORCEPROP 2 LAST CDS_LIB mstr_standard
J 0
(-6375 2150);
DISPLAY 0.489362 (-6375 2150);
PAINT ORANGE (-6375 2150);
DISPLAY INVISIBLE (-6375 2150);
FORCEPROP 1 LAST OFFPAGE TRUE
J 0
(-6050 2025);
PAINT GREEN (-6050 2025);
DISPLAY INVISIBLE (-6050 2025);
FORCEPROP 1 LAST COMMENT_BODY TRUE
J 0
(-6275 2075);
DISPLAY 0.680851 (-6275 2075);
PAINT PEACH (-6275 2075);
DISPLAY INVISIBLE (-6275 2075);
FORCEPROP 2 LAST PATH I38
J 0
(-6650 2200);
DISPLAY 1.021277 (-6650 2200);
PAINT ORANGE (-6650 2200);
DISPLAY INVISIBLE (-6650 2200);
FORCEADD OFFPAGE..5
(-6175 2050);
FORCEPROP 2 LAST $XR0 212 
J 0
(-6460 2050);
DISPLAY 0.638298 (-6460 2050);
PAINT MONO (-6460 2050);
FORCEPROP 2 LAST CDS_LIB mstr_standard
J 0
(-6175 2050);
DISPLAY 0.489362 (-6175 2050);
PAINT ORANGE (-6175 2050);
DISPLAY INVISIBLE (-6175 2050);
FORCEPROP 1 LAST OFFPAGE TRUE
J 0
(-5850 1925);
PAINT GREEN (-5850 1925);
DISPLAY INVISIBLE (-5850 1925);
FORCEPROP 1 LAST COMMENT_BODY TRUE
J 0
(-6075 1975);
DISPLAY 0.680851 (-6075 1975);
PAINT PEACH (-6075 1975);
DISPLAY INVISIBLE (-6075 1975);
FORCEPROP 2 LAST PATH I39
J 0
(-6450 2100);
DISPLAY 1.021277 (-6450 2100);
PAINT ORANGE (-6450 2100);
DISPLAY INVISIBLE (-6450 2100);
FORCEADD OFFPAGE..5
(-6175 2000);
FORCEPROP 2 LAST $XR0 212 
J 0
(-6460 2000);
DISPLAY 0.638298 (-6460 2000);
PAINT MONO (-6460 2000);
FORCEPROP 2 LAST CDS_LIB mstr_standard
J 0
(-6175 2000);
DISPLAY 0.489362 (-6175 2000);
PAINT ORANGE (-6175 2000);
DISPLAY INVISIBLE (-6175 2000);
FORCEPROP 1 LAST OFFPAGE TRUE
J 0
(-5850 1875);
PAINT GREEN (-5850 1875);
DISPLAY INVISIBLE (-5850 1875);
FORCEPROP 1 LAST COMMENT_BODY TRUE
J 0
(-6075 1925);
DISPLAY 0.680851 (-6075 1925);
PAINT PEACH (-6075 1925);
DISPLAY INVISIBLE (-6075 1925);
FORCEPROP 2 LAST PATH I40
J 0
(-6450 2050);
DISPLAY 1.021277 (-6450 2050);
PAINT ORANGE (-6450 2050);
DISPLAY INVISIBLE (-6450 2050);
FORCEADD PRELIM..10
(-4290 3340);
PAINT GRAY (-4290 3340);
FORCEPROP 2 LAST CDS_LIB mstr_misc
J 0
(-4290 3340);
DISPLAY 0.489362 (-4290 3340);
PAINT ORANGE (-4290 3340);
DISPLAY INVISIBLE (-4290 3340);
FORCEPROP 1 LAST COMMENT_BODY TRUE
J 0
(-4290 3340);
DISPLAY 0.489362 (-4290 3340);
PAINT PEACH (-4290 3340);
DISPLAY INVISIBLE (-4290 3340);
FORCEADD DESIGN_NOTE..1
(-5000 650);
FORCEPROP 0 LAST L1 CPU SYMBOLS 1-30 ARE PRELIMINARY AND SUBJECT TO CHANGE
J 0
(-5200 525);
DISPLAY 1.021277 (-5200 525);
PAINT ORANGE (-5200 525);
FORCEPROP 2 LAST CDS_LIB mstr_symbols
J 0
(-5000 650);
PAINT ORANGE (-5000 650);
DISPLAY INVISIBLE (-5000 650);
FORCEPROP 1 LAST COMMENT_BODY TRUE
J 0
(-4975 750);
DISPLAY 0.978723 (-4975 750);
PAINT ORANGE (-4975 750);
DISPLAY INVISIBLE (-4975 750);
FORCEADD INTEL_CORP_BPAGE..1
(0 0);
FORCEPROP 1 LAST CDS_CON_LAST_MODIFIED Tue Dec 01 11:51:24 2015
J 0
(-1425 325);
DISPLAY 1.340426 (-1425 325);
PAINT GREEN (-1425 325);
DISPLAY INVISIBLE (-1425 325);
FORCEPROP 1 LAST CUSTOM_TXT_CDS <CURRENT_DESIGN_SHEET> OF <TOTAL_DESIGN_SHEETS>
J 0
(-500 25);
PAINT GREEN (-500 25);
FORCEPROP 1 LAST CUSTOM_TXT_CDS <CON_LAST_MODIFIED>
J 0
(-1925 350);
PAINT GREEN (-1925 350);
FORCEPROP 2 LAST CUSTOM_TXT_CDS <XR_PAGE_TITLE>
J 0
(-7890 5250);
DISPLAY 0.638298 (-7890 5250);
PAINT PINK (-7890 5250);
DISPLAY INVISIBLE (-7890 5250);
FORCEPROP 1 LAST SCH_ADDRESS3 Santa Clara, CA 95052-8119
J 0
(-3975 25);
DISPLAY 0.617021 (-3975 25);
PAINT GREEN (-3975 25);
FORCEPROP 1 LAST SCH_ADDRESS2 P.O. BOX 58119
J 0
(-3975 75);
DISPLAY 0.617021 (-3975 75);
PAINT GREEN (-3975 75);
FORCEPROP 1 LAST SCH_ADDRESS1 2200 Mission College Blvd.
J 0
(-3975 125);
DISPLAY 0.617021 (-3975 125);
PAINT GREEN (-3975 125);
FORCEPROP 1 LAST SCH_TITLE SKYLAKE - SKT0 - 19 OF 21
J 0
(-7950 50);
DISPLAY 1.212766 (-7950 50);
PAINT GREEN (-7950 50);
FORCEPROP 1 LAST SCH_NUMBER H4694802
J 0
(-1300 150);
DISPLAY 1.212766 (-1300 150);
PAINT YELLOW (-1300 150);
FORCEPROP 1 LAST SCH_DEPT BESD
J 1
(-4450 100);
DISPLAY 1.212766 (-4450 100);
PAINT YELLOW (-4450 100);
FORCEPROP 1 LAST SCH_REV 2.420
J 0
(-250 150);
DISPLAY 0.978723 (-250 150);
PAINT YELLOW (-250 150);
FORCEPROP 2 LAST CDS_LIB mstr_symbols
J 0
(0 0);
PAINT ORANGE (0 0);
DISPLAY INVISIBLE (0 0);
FORCEPROP 2 LAST PAGE_BORDER TRUE
J 0
(-7890 5250);
DISPLAY 0.851064 (-7890 5250);
PAINT PINK (-7890 5250);
DISPLAY INVISIBLE (-7890 5250);
FORCEPROP 1 LAST COMMENT_BODY TRUE
J 0
(12 12);
DISPLAY 0.638298 (12 12);
PAINT GREEN (12 12);
DISPLAY INVISIBLE (12 12);
FORCEPROP 2 LAST CDS_XR_PAGE_TITLE CR-39 : @BASEBOARD_FAB2_LIB.BASEBOARD_FAB2(SCH_1):PAGE39
J 0
(-7890 5250);
DISPLAY 0.638298 (-7890 5250);
PAINT PINK (-7890 5250);
DISPLAY INVISIBLE (-7890 5250);
WIRE 16 -1 (-3200 3550)(-2250 3550);
WIRE 16 -1 (-2250 3550)(-2250 3850);
WIRE 16 -1 (-3200 3850)(-2250 3850);
WIRE 16 -1 (-2250 3850)(-2250 3975);
WIRE 16 -1 (-5475 2800)(-5300 2800);
WIRE 16 -1 (-5475 2750)(-5475 2800);
WIRE 16 -1 (-5300 2750)(-5475 2750);
WIRE 16 -1 (-5475 2750)(-5475 2700);
WIRE 16 -1 (-5475 2700)(-5300 2700);
WIRE 16 -1 (-5475 2700)(-5475 2600);
WIRE 16 -1 (-5475 2600)(-5300 2600);
WIRE 16 -1 (-6025 2600)(-5475 2600);
WIRE 16 -1 (-6025 2825)(-6025 2600);
WIRE 16 -1 (-5300 1250)(-5475 1250);
WIRE 16 -1 (-5475 1400)(-5475 1250);
WIRE 16 -1 (-5475 1400)(-5475 1550);
WIRE 16 -1 (-5475 1400)(-5300 1400);
WIRE 16 -1 (-5475 1550)(-5300 1550);
WIRE 16 -1 (-5475 1550)(-5475 1700);
WIRE 16 -1 (-5475 1700)(-5300 1700);
WIRE 16 -1 (-5475 1700)(-5475 1850);
WIRE 16 -1 (-5300 1850)(-5475 1850);
WIRE 16 -1 (-5475 1850)(-6825 1850);
WIRE 16 -1 (-6825 1850)(-6825 1900);
WIRE 16 -1 (-5650 2900)(-5300 2900);
WIRE 16 -1 (-5650 2950)(-5650 2900);
WIRE 16 -1 (-5650 2950)(-5300 2950);
WIRE 16 -1 (-5650 3000)(-5650 2950);
WIRE 16 -1 (-5650 3000)(-5300 3000);
WIRE 16 -1 (-5650 3050)(-5650 3000);
WIRE 16 -1 (-5650 3100)(-5650 3050);
WIRE 16 -1 (-5650 3050)(-5300 3050);
WIRE 16 -1 (-5650 3100)(-5300 3100);
WIRE 16 -1 (-5650 3150)(-5650 3100);
WIRE 16 -1 (-5650 3150)(-5300 3150);
WIRE 16 -1 (-5650 3200)(-5650 3150);
WIRE 16 -1 (-5650 3200)(-5300 3200);
WIRE 16 -1 (-5650 3250)(-5650 3200);
WIRE 16 -1 (-5650 3250)(-5300 3250);
WIRE 16 -1 (-5650 3300)(-5650 3250);
WIRE 16 -1 (-5650 3300)(-5300 3300);
WIRE 16 -1 (-5650 3350)(-5650 3300);
WIRE 16 -1 (-5650 3350)(-5300 3350);
WIRE 16 -1 (-5650 3350)(-5650 3450);
WIRE 16 -1 (-5650 3450)(-5300 3450);
WIRE 16 -1 (-5650 3500)(-5650 3450);
WIRE 16 -1 (-5650 3500)(-5300 3500);
WIRE 16 -1 (-5650 3550)(-5650 3500);
WIRE 16 -1 (-5650 3550)(-5300 3550);
WIRE 16 -1 (-5650 3600)(-5650 3550);
WIRE 16 -1 (-5650 3600)(-5300 3600);
WIRE 16 -1 (-5650 3650)(-5650 3600);
WIRE 16 -1 (-5650 3650)(-5300 3650);
WIRE 16 -1 (-5650 3700)(-5650 3650);
WIRE 16 -1 (-5650 3700)(-5300 3700);
WIRE 16 -1 (-5650 3700)(-5650 3750);
WIRE 16 -1 (-5650 3750)(-5300 3750);
WIRE 16 -1 (-5650 3750)(-5650 3800);
WIRE 16 -1 (-5650 3800)(-5300 3800);
WIRE 16 -1 (-5650 3800)(-5650 3900);
WIRE 16 -1 (-5650 3900)(-5300 3900);
WIRE 16 -1 (-5650 3900)(-5650 3950);
WIRE 16 -1 (-5650 3950)(-5650 4125);
WIRE 16 -1 (-5650 3950)(-5300 3950);
WIRE 16 -1 (-5300 2350)(-6350 2350);
FORCEPROP 2 LAST SIG_NAME VSENSE_PVCCMCP_CPU0_SKT_VSEN
J 0
(-6335 2360);
DISPLAY 0.617021 (-6335 2360);
PAINT ORANGE (-6335 2360);
WIRE 16 -1 (-6350 2300)(-5300 2300);
FORCEPROP 2 LAST SIG_NAME VSENSE_PVCCMCP_CPU0_SKT_VRTN
J 0
(-6335 2310);
DISPLAY 0.617021 (-6335 2310);
PAINT ORANGE (-6335 2310);
WIRE 16 -1 (-5300 2200)(-6325 2200);
FORCEPROP 2 LAST SIG_NAME VSENSE_PVCCIOMCP_CPU0_SKT_VSEN
J 0
(-6310 2210);
DISPLAY 0.617021 (-6310 2210);
PAINT ORANGE (-6310 2210);
WIRE 16 -1 (-6325 2150)(-5300 2150);
FORCEPROP 2 LAST SIG_NAME VSENSE_PVCCIOMCP_CPU0_SKT_VRTN
J 0
(-6310 2160);
DISPLAY 0.617021 (-6310 2160);
PAINT ORANGE (-6310 2160);
WIRE 16 -1 (-5300 1200)(-6075 1200);
FORCEPROP 0 LAST SIG_NAME TP_CPU0_RSVD_61
J 0
(-6060 1210);
DISPLAY 0.617021 (-6060 1210);
PAINT ORANGE (-6060 1210);
FORCEPROP 2 LASTPROP $XRERR UNIQUE?
J 0
(-6315 1200);
DISPLAY 0.638298 (-6315 1200);
PAINT MONO (-6315 1200);
DISPLAY INVISIBLE (-6315 1200);
WIRE 16 -1 (-5300 1300)(-6075 1300);
FORCEPROP 0 LAST SIG_NAME TP_CPU0_KTI2_DFX_DN
J 0
(-6085 1310);
DISPLAY 0.617021 (-6085 1310);
PAINT ORANGE (-6085 1310);
FORCEPROP 2 LASTPROP $XRERR UNIQUE?
J 0
(-6315 1300);
DISPLAY 0.638298 (-6315 1300);
PAINT MONO (-6315 1300);
DISPLAY INVISIBLE (-6315 1300);
WIRE 16 -1 (-5300 1350)(-6075 1350);
FORCEPROP 0 LAST SIG_NAME TP_CPU0_RSVD_64
J 0
(-6060 1360);
DISPLAY 0.617021 (-6060 1360);
PAINT ORANGE (-6060 1360);
FORCEPROP 2 LASTPROP $XRERR UNIQUE?
J 0
(-6315 1350);
DISPLAY 0.638298 (-6315 1350);
PAINT MONO (-6315 1350);
DISPLAY INVISIBLE (-6315 1350);
WIRE 16 -1 (-5300 1450)(-6075 1450);
FORCEPROP 0 LAST SIG_NAME TP_CPU0_RSVD_66
J 0
(-6060 1460);
DISPLAY 0.617021 (-6060 1460);
PAINT ORANGE (-6060 1460);
FORCEPROP 2 LASTPROP $XRERR UNIQUE?
J 0
(-6315 1450);
DISPLAY 0.638298 (-6315 1450);
PAINT MONO (-6315 1450);
DISPLAY INVISIBLE (-6315 1450);
WIRE 16 -1 (-5300 1500)(-6075 1500);
FORCEPROP 0 LAST SIG_NAME TP_CPU0_RSVD_67
J 0
(-6060 1510);
DISPLAY 0.617021 (-6060 1510);
PAINT ORANGE (-6060 1510);
FORCEPROP 2 LASTPROP $XRERR UNIQUE?
J 0
(-6315 1500);
DISPLAY 0.638298 (-6315 1500);
PAINT MONO (-6315 1500);
DISPLAY INVISIBLE (-6315 1500);
WIRE 16 -1 (-5300 1600)(-6075 1600);
FORCEPROP 0 LAST SIG_NAME TP_CPU0_RSVD_69
J 0
(-6060 1610);
DISPLAY 0.617021 (-6060 1610);
PAINT ORANGE (-6060 1610);
FORCEPROP 2 LASTPROP $XRERR UNIQUE?
J 0
(-6315 1600);
DISPLAY 0.638298 (-6315 1600);
PAINT MONO (-6315 1600);
DISPLAY INVISIBLE (-6315 1600);
WIRE 16 -1 (-5300 1650)(-6075 1650);
FORCEPROP 0 LAST SIG_NAME TP_CPU0_RSVD_70
J 0
(-6060 1660);
DISPLAY 0.617021 (-6060 1660);
PAINT ORANGE (-6060 1660);
FORCEPROP 2 LASTPROP $XRERR UNIQUE?
J 0
(-6315 1650);
DISPLAY 0.638298 (-6315 1650);
PAINT MONO (-6315 1650);
DISPLAY INVISIBLE (-6315 1650);
WIRE 16 -1 (-5300 1750)(-6075 1750);
FORCEPROP 0 LAST SIG_NAME TP_CPU0_RSVD_72
J 0
(-6060 1760);
DISPLAY 0.617021 (-6060 1760);
PAINT ORANGE (-6060 1760);
FORCEPROP 2 LASTPROP $XRERR UNIQUE?
J 0
(-6315 1750);
DISPLAY 0.638298 (-6315 1750);
PAINT MONO (-6315 1750);
DISPLAY INVISIBLE (-6315 1750);
WIRE 16 -1 (-5300 1800)(-6075 1800);
FORCEPROP 0 LAST SIG_NAME TP_CPU0_RSVD_73
J 0
(-6060 1810);
DISPLAY 0.617021 (-6060 1810);
PAINT ORANGE (-6060 1810);
FORCEPROP 2 LASTPROP $XRERR UNIQUE?
J 0
(-6315 1800);
DISPLAY 0.638298 (-6315 1800);
PAINT MONO (-6315 1800);
DISPLAY INVISIBLE (-6315 1800);
WIRE 16 -1 (-5300 1900)(-6100 1900);
FORCEPROP 0 LAST SIG_NAME PD_CPU0_MCP01_DMON
J 0
(-6085 1910);
DISPLAY 0.617021 (-6085 1910);
PAINT ORANGE (-6085 1910);
WIRE 16 -1 (-6125 2000)(-5300 2000);
FORCEPROP 2 LAST SIG_NAME VSENSE_PVCCIO_CPU0_SKT_VRTN
J 0
(-6110 2010);
DISPLAY 0.617021 (-6110 2010);
PAINT ORANGE (-6110 2010);
WIRE 16 -1 (-5300 2650)(-5925 2650);
FORCEPROP 0 LAST SIG_NAME TP_CPU0_KTI2_AMONV
J 0
(-5935 2660);
DISPLAY 0.617021 (-5935 2660);
PAINT ORANGE (-5935 2660);
FORCEPROP 2 LASTPROP $XRERR UNIQUE?
J 0
(-6165 2650);
DISPLAY 0.638298 (-6165 2650);
PAINT MONO (-6165 2650);
DISPLAY INVISIBLE (-6165 2650);
WIRE 16 -1 (-6125 2500)(-5300 2500);
FORCEPROP 2 LAST SIG_NAME VSENSE_PVSA_CPU0_SKT_VSEN
J 0
(-6110 2510);
DISPLAY 0.617021 (-6110 2510);
PAINT ORANGE (-6110 2510);
WIRE 16 -1 (-6125 2450)(-5300 2450);
FORCEPROP 2 LAST SIG_NAME VSENSE_PVSA_CPU0_SKT_VRTN
J 0
(-6110 2460);
DISPLAY 0.617021 (-6110 2460);
PAINT ORANGE (-6110 2460);
WIRE 16 -1 (-5300 2050)(-6125 2050);
FORCEPROP 2 LAST SIG_NAME VSENSE_PVCCIO_CPU0_SKT_VSEN
J 0
(-6110 2060);
DISPLAY 0.617021 (-6110 2060);
PAINT ORANGE (-6110 2060);
WIRE 16 -1 (-3200 950)(-2525 950);
FORCEPROP 0 LAST SIG_NAME TP_CPU0_RSVD_0
J 0
(-2935 960);
DISPLAY 0.617021 (-2935 960);
PAINT ORANGE (-2935 960);
FORCEPROP 2 LASTPROP $XRERR UNIQUE?
J 0
(-2495 950);
DISPLAY 0.638298 (-2495 950);
PAINT MONO (-2495 950);
DISPLAY INVISIBLE (-2495 950);
WIRE 16 -1 (-3200 1000)(-2525 1000);
FORCEPROP 0 LAST SIG_NAME TP_CPU0_RSVD_1
J 0
(-2935 1010);
DISPLAY 0.617021 (-2935 1010);
PAINT ORANGE (-2935 1010);
FORCEPROP 2 LASTPROP $XRERR UNIQUE?
J 0
(-2495 1000);
DISPLAY 0.638298 (-2495 1000);
PAINT MONO (-2495 1000);
DISPLAY INVISIBLE (-2495 1000);
WIRE 16 -1 (-3200 1050)(-2525 1050);
FORCEPROP 0 LAST SIG_NAME TP_CPU0_RSVD_2
J 0
(-2935 1060);
DISPLAY 0.617021 (-2935 1060);
PAINT ORANGE (-2935 1060);
FORCEPROP 2 LASTPROP $XRERR UNIQUE?
J 0
(-2495 1050);
DISPLAY 0.638298 (-2495 1050);
PAINT MONO (-2495 1050);
DISPLAY INVISIBLE (-2495 1050);
WIRE 16 -1 (-3200 1100)(-2525 1100);
FORCEPROP 0 LAST SIG_NAME TP_CPU0_RSVD_3
J 0
(-2935 1110);
DISPLAY 0.617021 (-2935 1110);
PAINT ORANGE (-2935 1110);
FORCEPROP 2 LASTPROP $XRERR UNIQUE?
J 0
(-2495 1100);
DISPLAY 0.638298 (-2495 1100);
PAINT MONO (-2495 1100);
DISPLAY INVISIBLE (-2495 1100);
WIRE 16 -1 (-3200 1150)(-2525 1150);
FORCEPROP 0 LAST SIG_NAME TP_CPU0_RSVD_4
J 0
(-2935 1160);
DISPLAY 0.617021 (-2935 1160);
PAINT ORANGE (-2935 1160);
FORCEPROP 2 LASTPROP $XRERR UNIQUE?
J 0
(-2495 1150);
DISPLAY 0.638298 (-2495 1150);
PAINT MONO (-2495 1150);
DISPLAY INVISIBLE (-2495 1150);
WIRE 16 -1 (-3200 1200)(-2525 1200);
FORCEPROP 0 LAST SIG_NAME TP_CPU0_RSVD_5
J 0
(-2935 1210);
DISPLAY 0.617021 (-2935 1210);
PAINT ORANGE (-2935 1210);
FORCEPROP 2 LASTPROP $XRERR UNIQUE?
J 0
(-2495 1200);
DISPLAY 0.638298 (-2495 1200);
PAINT MONO (-2495 1200);
DISPLAY INVISIBLE (-2495 1200);
WIRE 16 -1 (-3200 1250)(-2525 1250);
FORCEPROP 0 LAST SIG_NAME TP_CPU0_RSVD_6
J 0
(-2935 1260);
DISPLAY 0.617021 (-2935 1260);
PAINT ORANGE (-2935 1260);
FORCEPROP 2 LASTPROP $XRERR UNIQUE?
J 0
(-2495 1250);
DISPLAY 0.638298 (-2495 1250);
PAINT MONO (-2495 1250);
DISPLAY INVISIBLE (-2495 1250);
WIRE 16 -1 (-3200 1300)(-2525 1300);
FORCEPROP 0 LAST SIG_NAME TP_CPU0_RSVD_7
J 0
(-2935 1310);
DISPLAY 0.617021 (-2935 1310);
PAINT ORANGE (-2935 1310);
FORCEPROP 2 LASTPROP $XRERR UNIQUE?
J 0
(-2495 1300);
DISPLAY 0.638298 (-2495 1300);
PAINT MONO (-2495 1300);
DISPLAY INVISIBLE (-2495 1300);
WIRE 16 -1 (-3200 1350)(-2525 1350);
FORCEPROP 0 LAST SIG_NAME TP_CPU0_RSVD_8
J 0
(-2935 1360);
DISPLAY 0.617021 (-2935 1360);
PAINT ORANGE (-2935 1360);
FORCEPROP 2 LASTPROP $XRERR UNIQUE?
J 0
(-2495 1350);
DISPLAY 0.638298 (-2495 1350);
PAINT MONO (-2495 1350);
DISPLAY INVISIBLE (-2495 1350);
WIRE 16 -1 (-3200 1400)(-2525 1400);
FORCEPROP 0 LAST SIG_NAME TP_CPU0_RSVD_9
J 0
(-2935 1410);
DISPLAY 0.617021 (-2935 1410);
PAINT ORANGE (-2935 1410);
FORCEPROP 2 LASTPROP $XRERR UNIQUE?
J 0
(-2495 1400);
DISPLAY 0.638298 (-2495 1400);
PAINT MONO (-2495 1400);
DISPLAY INVISIBLE (-2495 1400);
WIRE 16 -1 (-3200 1450)(-2525 1450);
FORCEPROP 0 LAST SIG_NAME TP_CPU0_RSVD_10
J 0
(-2935 1460);
DISPLAY 0.617021 (-2935 1460);
PAINT ORANGE (-2935 1460);
FORCEPROP 2 LASTPROP $XRERR UNIQUE?
J 0
(-2495 1450);
DISPLAY 0.638298 (-2495 1450);
PAINT MONO (-2495 1450);
DISPLAY INVISIBLE (-2495 1450);
WIRE 16 -1 (-3200 1500)(-2525 1500);
FORCEPROP 0 LAST SIG_NAME TP_CPU0_RSVD_11
J 0
(-2935 1510);
DISPLAY 0.617021 (-2935 1510);
PAINT ORANGE (-2935 1510);
FORCEPROP 2 LASTPROP $XRERR UNIQUE?
J 0
(-2495 1500);
DISPLAY 0.638298 (-2495 1500);
PAINT MONO (-2495 1500);
DISPLAY INVISIBLE (-2495 1500);
WIRE 16 -1 (-3200 1550)(-2525 1550);
FORCEPROP 0 LAST SIG_NAME TP_CPU0_RSVD_12
J 0
(-2935 1560);
DISPLAY 0.617021 (-2935 1560);
PAINT ORANGE (-2935 1560);
FORCEPROP 2 LASTPROP $XRERR UNIQUE?
J 0
(-2495 1550);
DISPLAY 0.638298 (-2495 1550);
PAINT MONO (-2495 1550);
DISPLAY INVISIBLE (-2495 1550);
WIRE 16 -1 (-3200 1600)(-2525 1600);
FORCEPROP 0 LAST SIG_NAME TP_CPU0_RSVD_13
J 0
(-2935 1610);
DISPLAY 0.617021 (-2935 1610);
PAINT ORANGE (-2935 1610);
FORCEPROP 2 LASTPROP $XRERR UNIQUE?
J 0
(-2495 1600);
DISPLAY 0.638298 (-2495 1600);
PAINT MONO (-2495 1600);
DISPLAY INVISIBLE (-2495 1600);
WIRE 16 -1 (-3200 1650)(-2525 1650);
FORCEPROP 0 LAST SIG_NAME TP_CPU0_RSVD_14
J 0
(-2935 1660);
DISPLAY 0.617021 (-2935 1660);
PAINT ORANGE (-2935 1660);
FORCEPROP 2 LASTPROP $XRERR UNIQUE?
J 0
(-2495 1650);
DISPLAY 0.638298 (-2495 1650);
PAINT MONO (-2495 1650);
DISPLAY INVISIBLE (-2495 1650);
WIRE 16 -1 (-3200 1700)(-2525 1700);
FORCEPROP 0 LAST SIG_NAME TP_CPU0_RSVD_15
J 0
(-2935 1710);
DISPLAY 0.617021 (-2935 1710);
PAINT ORANGE (-2935 1710);
FORCEPROP 2 LASTPROP $XRERR UNIQUE?
J 0
(-2495 1700);
DISPLAY 0.638298 (-2495 1700);
PAINT MONO (-2495 1700);
DISPLAY INVISIBLE (-2495 1700);
WIRE 16 -1 (-3200 1750)(-2525 1750);
FORCEPROP 0 LAST SIG_NAME TP_CPU0_RSVD_16
J 0
(-2935 1760);
DISPLAY 0.617021 (-2935 1760);
PAINT ORANGE (-2935 1760);
FORCEPROP 2 LASTPROP $XRERR UNIQUE?
J 0
(-2495 1750);
DISPLAY 0.638298 (-2495 1750);
PAINT MONO (-2495 1750);
DISPLAY INVISIBLE (-2495 1750);
WIRE 16 -1 (-3200 1800)(-2525 1800);
FORCEPROP 0 LAST SIG_NAME TP_CPU0_RSVD_17
J 0
(-2935 1810);
DISPLAY 0.617021 (-2935 1810);
PAINT ORANGE (-2935 1810);
FORCEPROP 2 LASTPROP $XRERR UNIQUE?
J 0
(-2495 1800);
DISPLAY 0.638298 (-2495 1800);
PAINT MONO (-2495 1800);
DISPLAY INVISIBLE (-2495 1800);
WIRE 16 -1 (-3200 1850)(-2525 1850);
FORCEPROP 0 LAST SIG_NAME TP_CPU0_RSVD_18
J 0
(-2935 1860);
DISPLAY 0.617021 (-2935 1860);
PAINT ORANGE (-2935 1860);
FORCEPROP 2 LASTPROP $XRERR UNIQUE?
J 0
(-2495 1850);
DISPLAY 0.638298 (-2495 1850);
PAINT MONO (-2495 1850);
DISPLAY INVISIBLE (-2495 1850);
WIRE 16 -1 (-3200 1900)(-2525 1900);
FORCEPROP 0 LAST SIG_NAME TP_CPU0_RSVD_19
J 0
(-2935 1910);
DISPLAY 0.617021 (-2935 1910);
PAINT ORANGE (-2935 1910);
FORCEPROP 2 LASTPROP $XRERR UNIQUE?
J 0
(-2495 1900);
DISPLAY 0.638298 (-2495 1900);
PAINT MONO (-2495 1900);
DISPLAY INVISIBLE (-2495 1900);
WIRE 16 -1 (-3200 1950)(-2525 1950);
FORCEPROP 0 LAST SIG_NAME TP_CPU0_RSVD_20
J 0
(-2935 1960);
DISPLAY 0.617021 (-2935 1960);
PAINT ORANGE (-2935 1960);
FORCEPROP 2 LASTPROP $XRERR UNIQUE?
J 0
(-2495 1950);
DISPLAY 0.638298 (-2495 1950);
PAINT MONO (-2495 1950);
DISPLAY INVISIBLE (-2495 1950);
WIRE 16 -1 (-3200 2000)(-2525 2000);
FORCEPROP 0 LAST SIG_NAME TP_CPU0_RSVD_21
J 0
(-2935 2010);
DISPLAY 0.617021 (-2935 2010);
PAINT ORANGE (-2935 2010);
FORCEPROP 2 LASTPROP $XRERR UNIQUE?
J 0
(-2495 2000);
DISPLAY 0.638298 (-2495 2000);
PAINT MONO (-2495 2000);
DISPLAY INVISIBLE (-2495 2000);
WIRE 16 -1 (-3200 2050)(-2525 2050);
FORCEPROP 0 LAST SIG_NAME TP_CPU0_RSVD_22
J 0
(-2935 2060);
DISPLAY 0.617021 (-2935 2060);
PAINT ORANGE (-2935 2060);
FORCEPROP 2 LASTPROP $XRERR UNIQUE?
J 0
(-2495 2050);
DISPLAY 0.638298 (-2495 2050);
PAINT MONO (-2495 2050);
DISPLAY INVISIBLE (-2495 2050);
WIRE 16 -1 (-3200 2100)(-2525 2100);
FORCEPROP 0 LAST SIG_NAME TP_CPU0_RSVD_23
J 0
(-2935 2110);
DISPLAY 0.617021 (-2935 2110);
PAINT ORANGE (-2935 2110);
FORCEPROP 2 LASTPROP $XRERR UNIQUE?
J 0
(-2495 2100);
DISPLAY 0.638298 (-2495 2100);
PAINT MONO (-2495 2100);
DISPLAY INVISIBLE (-2495 2100);
WIRE 16 -1 (-3200 2150)(-2525 2150);
FORCEPROP 0 LAST SIG_NAME TP_CPU0_RSVD_24
J 0
(-2935 2160);
DISPLAY 0.617021 (-2935 2160);
PAINT ORANGE (-2935 2160);
FORCEPROP 2 LASTPROP $XRERR UNIQUE?
J 0
(-2495 2150);
DISPLAY 0.638298 (-2495 2150);
PAINT MONO (-2495 2150);
DISPLAY INVISIBLE (-2495 2150);
WIRE 16 -1 (-3200 2200)(-2525 2200);
FORCEPROP 0 LAST SIG_NAME TP_CPU0_RSVD_25
J 0
(-2935 2210);
DISPLAY 0.617021 (-2935 2210);
PAINT ORANGE (-2935 2210);
FORCEPROP 2 LASTPROP $XRERR UNIQUE?
J 0
(-2495 2200);
DISPLAY 0.638298 (-2495 2200);
PAINT MONO (-2495 2200);
DISPLAY INVISIBLE (-2495 2200);
WIRE 16 -1 (-3200 2250)(-2525 2250);
FORCEPROP 0 LAST SIG_NAME TP_CPU0_RSVD_26
J 0
(-2935 2260);
DISPLAY 0.617021 (-2935 2260);
PAINT ORANGE (-2935 2260);
FORCEPROP 2 LASTPROP $XRERR UNIQUE?
J 0
(-2495 2250);
DISPLAY 0.638298 (-2495 2250);
PAINT MONO (-2495 2250);
DISPLAY INVISIBLE (-2495 2250);
WIRE 16 -1 (-3200 2300)(-2525 2300);
FORCEPROP 0 LAST SIG_NAME TP_CPU0_RSVD_27
J 0
(-2935 2310);
DISPLAY 0.617021 (-2935 2310);
PAINT ORANGE (-2935 2310);
FORCEPROP 2 LASTPROP $XRERR UNIQUE?
J 0
(-2495 2300);
DISPLAY 0.638298 (-2495 2300);
PAINT MONO (-2495 2300);
DISPLAY INVISIBLE (-2495 2300);
WIRE 16 -1 (-3200 2350)(-2525 2350);
FORCEPROP 0 LAST SIG_NAME TP_CPU0_RSVD_28
J 0
(-2935 2360);
DISPLAY 0.617021 (-2935 2360);
PAINT ORANGE (-2935 2360);
FORCEPROP 2 LASTPROP $XRERR UNIQUE?
J 0
(-2495 2350);
DISPLAY 0.638298 (-2495 2350);
PAINT MONO (-2495 2350);
DISPLAY INVISIBLE (-2495 2350);
WIRE 16 -1 (-3200 2400)(-2525 2400);
FORCEPROP 0 LAST SIG_NAME TP_CPU0_RSVD_29
J 0
(-2935 2410);
DISPLAY 0.617021 (-2935 2410);
PAINT ORANGE (-2935 2410);
FORCEPROP 2 LASTPROP $XRERR UNIQUE?
J 0
(-2495 2400);
DISPLAY 0.638298 (-2495 2400);
PAINT MONO (-2495 2400);
DISPLAY INVISIBLE (-2495 2400);
WIRE 16 -1 (-3200 2450)(-2525 2450);
FORCEPROP 0 LAST SIG_NAME TP_CPU0_RSVD_30
J 0
(-2935 2460);
DISPLAY 0.617021 (-2935 2460);
PAINT ORANGE (-2935 2460);
FORCEPROP 2 LASTPROP $XRERR UNIQUE?
J 0
(-2495 2450);
DISPLAY 0.638298 (-2495 2450);
PAINT MONO (-2495 2450);
DISPLAY INVISIBLE (-2495 2450);
WIRE 16 -1 (-3200 2500)(-2525 2500);
FORCEPROP 0 LAST SIG_NAME TP_CPU0_RSVD_31
J 0
(-2935 2510);
DISPLAY 0.617021 (-2935 2510);
PAINT ORANGE (-2935 2510);
FORCEPROP 2 LASTPROP $XRERR UNIQUE?
J 0
(-2495 2500);
DISPLAY 0.638298 (-2495 2500);
PAINT MONO (-2495 2500);
DISPLAY INVISIBLE (-2495 2500);
WIRE 16 -1 (-3200 2550)(-2525 2550);
FORCEPROP 0 LAST SIG_NAME TP_CPU0_RSVD_32
J 0
(-2935 2560);
DISPLAY 0.617021 (-2935 2560);
PAINT ORANGE (-2935 2560);
FORCEPROP 2 LASTPROP $XRERR UNIQUE?
J 0
(-2495 2550);
DISPLAY 0.638298 (-2495 2550);
PAINT MONO (-2495 2550);
DISPLAY INVISIBLE (-2495 2550);
WIRE 16 -1 (-3200 2600)(-2525 2600);
FORCEPROP 0 LAST SIG_NAME TP_CPU0_RSVD_33
J 0
(-2935 2610);
DISPLAY 0.617021 (-2935 2610);
PAINT ORANGE (-2935 2610);
FORCEPROP 2 LASTPROP $XRERR UNIQUE?
J 0
(-2495 2600);
DISPLAY 0.638298 (-2495 2600);
PAINT MONO (-2495 2600);
DISPLAY INVISIBLE (-2495 2600);
WIRE 16 -1 (-3200 2650)(-2525 2650);
FORCEPROP 0 LAST SIG_NAME TP_CPU0_RSVD_34
J 0
(-2935 2660);
DISPLAY 0.617021 (-2935 2660);
PAINT ORANGE (-2935 2660);
FORCEPROP 2 LASTPROP $XRERR UNIQUE?
J 0
(-2495 2650);
DISPLAY 0.638298 (-2495 2650);
PAINT MONO (-2495 2650);
DISPLAY INVISIBLE (-2495 2650);
WIRE 16 -1 (-3200 2700)(-2525 2700);
FORCEPROP 0 LAST SIG_NAME TP_CPU0_RSVD_35
J 0
(-2935 2710);
DISPLAY 0.617021 (-2935 2710);
PAINT ORANGE (-2935 2710);
FORCEPROP 2 LASTPROP $XRERR UNIQUE?
J 0
(-2495 2700);
DISPLAY 0.638298 (-2495 2700);
PAINT MONO (-2495 2700);
DISPLAY INVISIBLE (-2495 2700);
WIRE 16 -1 (-3200 2750)(-2525 2750);
FORCEPROP 0 LAST SIG_NAME TP_CPU0_RSVD_36
J 0
(-2935 2760);
DISPLAY 0.617021 (-2935 2760);
PAINT ORANGE (-2935 2760);
FORCEPROP 2 LASTPROP $XRERR UNIQUE?
J 0
(-2495 2750);
DISPLAY 0.638298 (-2495 2750);
PAINT MONO (-2495 2750);
DISPLAY INVISIBLE (-2495 2750);
WIRE 16 -1 (-3200 2800)(-2525 2800);
FORCEPROP 0 LAST SIG_NAME TP_CPU0_RSVD_37
J 0
(-2935 2810);
DISPLAY 0.617021 (-2935 2810);
PAINT ORANGE (-2935 2810);
FORCEPROP 2 LASTPROP $XRERR UNIQUE?
J 0
(-2495 2800);
DISPLAY 0.638298 (-2495 2800);
PAINT MONO (-2495 2800);
DISPLAY INVISIBLE (-2495 2800);
WIRE 16 -1 (-3200 2850)(-2525 2850);
FORCEPROP 0 LAST SIG_NAME TP_CPU0_RSVD_38
J 0
(-2935 2860);
DISPLAY 0.617021 (-2935 2860);
PAINT ORANGE (-2935 2860);
FORCEPROP 2 LASTPROP $XRERR UNIQUE?
J 0
(-2495 2850);
DISPLAY 0.638298 (-2495 2850);
PAINT MONO (-2495 2850);
DISPLAY INVISIBLE (-2495 2850);
WIRE 16 -1 (-3200 2900)(-2525 2900);
FORCEPROP 0 LAST SIG_NAME TP_CPU0_RSVD_39
J 0
(-2935 2910);
DISPLAY 0.617021 (-2935 2910);
PAINT ORANGE (-2935 2910);
FORCEPROP 2 LASTPROP $XRERR UNIQUE?
J 0
(-2495 2900);
DISPLAY 0.638298 (-2495 2900);
PAINT MONO (-2495 2900);
DISPLAY INVISIBLE (-2495 2900);
WIRE 16 -1 (-3200 2950)(-2525 2950);
FORCEPROP 0 LAST SIG_NAME TP_CPU0_RSVD_40
J 0
(-2935 2960);
DISPLAY 0.617021 (-2935 2960);
PAINT ORANGE (-2935 2960);
FORCEPROP 2 LASTPROP $XRERR UNIQUE?
J 0
(-2495 2950);
DISPLAY 0.638298 (-2495 2950);
PAINT MONO (-2495 2950);
DISPLAY INVISIBLE (-2495 2950);
WIRE 16 -1 (-3200 3000)(-2525 3000);
FORCEPROP 0 LAST SIG_NAME TP_CPU0_RSVD_41
J 0
(-2935 3010);
DISPLAY 0.617021 (-2935 3010);
PAINT ORANGE (-2935 3010);
FORCEPROP 2 LASTPROP $XRERR UNIQUE?
J 0
(-2495 3000);
DISPLAY 0.638298 (-2495 3000);
PAINT MONO (-2495 3000);
DISPLAY INVISIBLE (-2495 3000);
WIRE 16 -1 (-3200 3050)(-2525 3050);
FORCEPROP 0 LAST SIG_NAME TP_CPU0_RSVD_42
J 0
(-2935 3060);
DISPLAY 0.617021 (-2935 3060);
PAINT ORANGE (-2935 3060);
FORCEPROP 2 LASTPROP $XRERR UNIQUE?
J 0
(-2495 3050);
DISPLAY 0.638298 (-2495 3050);
PAINT MONO (-2495 3050);
DISPLAY INVISIBLE (-2495 3050);
WIRE 16 -1 (-3200 3100)(-2525 3100);
FORCEPROP 0 LAST SIG_NAME TP_CPU0_RSVD_43
J 0
(-2935 3110);
DISPLAY 0.617021 (-2935 3110);
PAINT ORANGE (-2935 3110);
FORCEPROP 2 LASTPROP $XRERR UNIQUE?
J 0
(-2495 3100);
DISPLAY 0.638298 (-2495 3100);
PAINT MONO (-2495 3100);
DISPLAY INVISIBLE (-2495 3100);
WIRE 16 -1 (-3200 3150)(-2525 3150);
FORCEPROP 0 LAST SIG_NAME TP_CPU0_RSVD_44
J 0
(-2935 3160);
DISPLAY 0.617021 (-2935 3160);
PAINT ORANGE (-2935 3160);
FORCEPROP 2 LASTPROP $XRERR UNIQUE?
J 0
(-2495 3150);
DISPLAY 0.638298 (-2495 3150);
PAINT MONO (-2495 3150);
DISPLAY INVISIBLE (-2495 3150);
WIRE 16 -1 (-3200 3200)(-2525 3200);
FORCEPROP 0 LAST SIG_NAME TP_CPU0_RSVD_45
J 0
(-2935 3210);
DISPLAY 0.617021 (-2935 3210);
PAINT ORANGE (-2935 3210);
FORCEPROP 2 LASTPROP $XRERR UNIQUE?
J 0
(-2495 3200);
DISPLAY 0.638298 (-2495 3200);
PAINT MONO (-2495 3200);
DISPLAY INVISIBLE (-2495 3200);
WIRE 16 -1 (-3200 3250)(-2525 3250);
FORCEPROP 0 LAST SIG_NAME TP_CPU0_RSVD_46
J 0
(-2935 3260);
DISPLAY 0.617021 (-2935 3260);
PAINT ORANGE (-2935 3260);
FORCEPROP 2 LASTPROP $XRERR UNIQUE?
J 0
(-2495 3250);
DISPLAY 0.638298 (-2495 3250);
PAINT MONO (-2495 3250);
DISPLAY INVISIBLE (-2495 3250);
WIRE 16 -1 (-3200 3300)(-2525 3300);
FORCEPROP 0 LAST SIG_NAME TP_CPU0_RSVD_47
J 0
(-2935 3310);
DISPLAY 0.617021 (-2935 3310);
PAINT ORANGE (-2935 3310);
FORCEPROP 2 LASTPROP $XRERR UNIQUE?
J 0
(-2495 3300);
DISPLAY 0.638298 (-2495 3300);
PAINT MONO (-2495 3300);
DISPLAY INVISIBLE (-2495 3300);
WIRE 16 -1 (-3200 3350)(-2525 3350);
FORCEPROP 0 LAST SIG_NAME TP_CPU0_RSVD_48
J 0
(-2935 3360);
DISPLAY 0.617021 (-2935 3360);
PAINT ORANGE (-2935 3360);
FORCEPROP 2 LASTPROP $XRERR UNIQUE?
J 0
(-2495 3350);
DISPLAY 0.638298 (-2495 3350);
PAINT MONO (-2495 3350);
DISPLAY INVISIBLE (-2495 3350);
WIRE 16 -1 (-3200 3400)(-2525 3400);
FORCEPROP 0 LAST SIG_NAME TP_CPU0_RSVD_49
J 0
(-2935 3410);
DISPLAY 0.617021 (-2935 3410);
PAINT ORANGE (-2935 3410);
FORCEPROP 2 LASTPROP $XRERR UNIQUE?
J 0
(-2495 3400);
DISPLAY 0.638298 (-2495 3400);
PAINT MONO (-2495 3400);
DISPLAY INVISIBLE (-2495 3400);
WIRE 16 -1 (-3200 3450)(-2525 3450);
FORCEPROP 0 LAST SIG_NAME TP_CPU0_RSVD_50
J 0
(-2935 3460);
DISPLAY 0.617021 (-2935 3460);
PAINT ORANGE (-2935 3460);
FORCEPROP 2 LASTPROP $XRERR UNIQUE?
J 0
(-2495 3450);
DISPLAY 0.638298 (-2495 3450);
PAINT MONO (-2495 3450);
DISPLAY INVISIBLE (-2495 3450);
WIRE 16 -1 (-3200 3500)(-2525 3500);
FORCEPROP 0 LAST SIG_NAME TP_CPU0_RSVD_51
J 0
(-2935 3510);
DISPLAY 0.617021 (-2935 3510);
PAINT ORANGE (-2935 3510);
FORCEPROP 2 LASTPROP $XRERR UNIQUE?
J 0
(-2495 3500);
DISPLAY 0.638298 (-2495 3500);
PAINT MONO (-2495 3500);
DISPLAY INVISIBLE (-2495 3500);
WIRE 16 -1 (-3200 3600)(-2525 3600);
FORCEPROP 0 LAST SIG_NAME TP_CPU0_RSVD_53
J 0
(-2935 3610);
DISPLAY 0.617021 (-2935 3610);
PAINT ORANGE (-2935 3610);
FORCEPROP 2 LASTPROP $XRERR UNIQUE?
J 0
(-2495 3600);
DISPLAY 0.638298 (-2495 3600);
PAINT MONO (-2495 3600);
DISPLAY INVISIBLE (-2495 3600);
WIRE 16 -1 (-3200 3650)(-2525 3650);
FORCEPROP 0 LAST SIG_NAME TP_CPU0_RSVD_54
J 0
(-2935 3660);
DISPLAY 0.617021 (-2935 3660);
PAINT ORANGE (-2935 3660);
FORCEPROP 2 LASTPROP $XRERR UNIQUE?
J 0
(-2495 3650);
DISPLAY 0.638298 (-2495 3650);
PAINT MONO (-2495 3650);
DISPLAY INVISIBLE (-2495 3650);
WIRE 16 -1 (-3200 3700)(-2525 3700);
FORCEPROP 0 LAST SIG_NAME TP_CPU0_RSVD_55
J 0
(-2935 3710);
DISPLAY 0.617021 (-2935 3710);
PAINT ORANGE (-2935 3710);
FORCEPROP 2 LASTPROP $XRERR UNIQUE?
J 0
(-2495 3700);
DISPLAY 0.638298 (-2495 3700);
PAINT MONO (-2495 3700);
DISPLAY INVISIBLE (-2495 3700);
WIRE 16 -1 (-3200 3750)(-2525 3750);
FORCEPROP 0 LAST SIG_NAME TP_CPU0_RSVD_56
J 0
(-2935 3760);
DISPLAY 0.617021 (-2935 3760);
PAINT ORANGE (-2935 3760);
FORCEPROP 2 LASTPROP $XRERR UNIQUE?
J 0
(-2495 3750);
DISPLAY 0.638298 (-2495 3750);
PAINT MONO (-2495 3750);
DISPLAY INVISIBLE (-2495 3750);
WIRE 16 -1 (-3200 3800)(-2525 3800);
FORCEPROP 0 LAST SIG_NAME TP_CPU0_RSVD_57
J 0
(-2935 3810);
DISPLAY 0.617021 (-2935 3810);
PAINT ORANGE (-2935 3810);
FORCEPROP 2 LASTPROP $XRERR UNIQUE?
J 0
(-2495 3800);
DISPLAY 0.638298 (-2495 3800);
PAINT MONO (-2495 3800);
DISPLAY INVISIBLE (-2495 3800);
WIRE 16 -1 (-3200 3900)(-2525 3900);
FORCEPROP 0 LAST SIG_NAME TP_CPU0_RSVD_59
J 0
(-2935 3910);
DISPLAY 0.617021 (-2935 3910);
PAINT ORANGE (-2935 3910);
FORCEPROP 2 LASTPROP $XRERR UNIQUE?
J 0
(-2495 3900);
DISPLAY 0.638298 (-2495 3900);
PAINT MONO (-2495 3900);
DISPLAY INVISIBLE (-2495 3900);
WIRE 16 -1 (-3200 3950)(-2525 3950);
FORCEPROP 0 LAST SIG_NAME TP_CPU0_RSVD_60
J 0
(-2935 3960);
DISPLAY 0.617021 (-2935 3960);
PAINT ORANGE (-2935 3960);
FORCEPROP 2 LASTPROP $XRERR UNIQUE?
J 0
(-2495 3950);
DISPLAY 0.638298 (-2495 3950);
PAINT MONO (-2495 3950);
DISPLAY INVISIBLE (-2495 3950);
DOT 1 (-5650 2950);
DOT 1 (-5475 2700);
DOT 1 (-5475 1400);
DOT 1 (-5475 2750);
DOT 1 (-5650 3450);
DOT 1 (-5650 3100);
DOT 1 (-5650 3300);
DOT 1 (-5650 3950);
DOT 1 (-5650 3900);
DOT 1 (-5650 3800);
DOT 1 (-5650 3750);
DOT 1 (-5650 3600);
DOT 1 (-5650 3250);
DOT 1 (-5650 3200);
DOT 1 (-5650 3150);
DOT 1 (-5650 3050);
DOT 1 (-5650 3000);
DOT 1 (-5650 3350);
DOT 1 (-5650 3650);
DOT 1 (-5650 3700);
DOT 1 (-5650 3550);
DOT 1 (-5650 3500);
DOT 1 (-2250 3850);
DOT 1 (-5475 1850);
DOT 1 (-5475 1550);
DOT 1 (-5475 1700);
DOT 1 (-5475 2600);
FORCENOTE
ROOM=CPU0
(-7925 325) 0;
DISPLAY LEFT (-7925 325);
DISPLAY 1.723404 (-7925 325);
PAINT PURPLE (-7925 325);
FORCENOTE
BOM_COST=PROC_SOCKET
(-7925 200) 0;
DISPLAY LEFT (-7925 200);
DISPLAY 1.723404 (-7925 200);
PAINT PURPLE (-7925 200);
QUIT
